(kicad_pcb
	(version 20260206)
	(generator "pcbnew")
	(generator_version "10.0")
	(general
		(thickness 1.6)
		(legacy_teardrops no)
	)
	(paper "A4")
	(title_block
		(title "03242023_DA0F0TMBIJ0_F0T_Motherboard_J_brd_V01_OCP.brd")
		(comment 1 "Grand Teton / footprints 2679-2682 of 6105")
	)
	(layers
		(0 "F.Cu" signal "TOP")
		(4 "In1.Cu" signal "GND")
		(6 "In2.Cu" signal "IN1")
		(8 "In3.Cu" signal "GND1")
		(10 "In4.Cu" signal "IN2")
		(12 "In5.Cu" signal "GND2")
		(14 "In6.Cu" signal "IN3")
		(16 "In7.Cu" signal "GND3")
		(18 "In8.Cu" signal "VCC")
		(20 "In9.Cu" signal "VCC1")
		(22 "In10.Cu" signal "GND4")
		(24 "In11.Cu" signal "IN4")
		(26 "In12.Cu" signal "GND5")
		(28 "In13.Cu" signal "IN5")
		(30 "In14.Cu" signal "GND6")
		(32 "In15.Cu" signal "IN6")
		(34 "In16.Cu" signal "GND7")
		(2 "B.Cu" signal "BOTTOM")
		(9 "F.Adhes" user "F.Adhesive")
		(11 "B.Adhes" user "B.Adhesive")
		(13 "F.Paste" user "Package Geometry/Pastemask Top")
		(15 "B.Paste" user "Package Geometry/Pastemask Bottom")
		(5 "F.SilkS" user "Ref Des/Silkscreen Top")
		(7 "B.SilkS" user "Ref Des/Silkscreen Bottom")
		(1 "F.Mask" user "Board Geometry/Soldermask Top")
		(3 "B.Mask" user "Board Geometry/Soldermask Bottom")
		(17 "Dwgs.User" user "User.Drawings")
		(19 "Cmts.User" user "User.Comments")
		(21 "Eco1.User" user "User.Eco1")
		(23 "Eco2.User" user "User.Eco2")
		(25 "Edge.Cuts" user "Board Geometry/Outline")
		(27 "Margin" user)
		(31 "F.CrtYd" user "Package Geometry/Place Bound Top")
		(29 "B.CrtYd" user "Package Geometry/Place Bound Bottom")
		(35 "F.Fab" user "Ref Des/Assembly Top")
		(33 "B.Fab" user "Ref Des/Assembly Bottom")
	)
	(footprint ""
		(layer "F.Cu")
		(at 325.193914 -25.102312)
		(property "Reference" "R1202"
			(at 0 0 0)
			(layer "F.SilkS")
			(hide yes)
			(effects
				(font
					(size 1.27 1.27)
				)
			)
		)
		(property "Value" ""
			(at 0 0 0)
			(layer "F.Fab")
			(effects
				(font
					(size 1.27 1.27)
				)
			)
		)
		(duplicate_pad_numbers_are_jumpers no)
		(fp_line
			(start -0.7874 -0.4064)
			(end 0.7874 -0.4064)
			(stroke
				(width 0.1524)
				(type default)
			)
			(layer "F.SilkS")
		)
		(fp_line
			(start -0.7874 0.4064)
			(end -0.7874 -0.4064)
			(stroke
				(width 0.1524)
				(type default)
			)
			(layer "F.SilkS")
		)
		(fp_line
			(start 0.7874 -0.4064)
			(end 0.7874 0.4064)
			(stroke
				(width 0.1524)
				(type default)
			)
			(layer "F.SilkS")
		)
		(fp_line
			(start 0.7874 0.4064)
			(end -0.7874 0.4064)
			(stroke
				(width 0.1524)
				(type default)
			)
			(layer "F.SilkS")
		)
		(fp_line
			(start -0.67945 -0.305054)
			(end -0.12065 -0.305054)
			(stroke
				(width 0.1)
				(type default)
			)
			(layer "F.Fab")
		)
		(fp_line
			(start -0.67945 0.3048)
			(end -0.67945 -0.305054)
			(stroke
				(width 0.1)
				(type default)
			)
			(layer "F.Fab")
		)
		(fp_line
			(start -0.12065 -0.305054)
			(end -0.12065 -0.2794)
			(stroke
				(width 0.1)
				(type default)
			)
			(layer "F.Fab")
		)
		(fp_line
			(start -0.12065 -0.2794)
			(end 0.12065 -0.2794)
			(stroke
				(width 0.1)
				(type default)
			)
			(layer "F.Fab")
		)
		(fp_line
			(start -0.12065 0.2794)
			(end -0.12065 0.3048)
			(stroke
				(width 0.1)
				(type default)
			)
			(layer "F.Fab")
		)
		(fp_line
			(start -0.12065 0.3048)
			(end -0.67945 0.3048)
			(stroke
				(width 0.1)
				(type default)
			)
			(layer "F.Fab")
		)
		(fp_line
			(start 0.120396 0.2794)
			(end -0.12065 0.2794)
			(stroke
				(width 0.1)
				(type default)
			)
			(layer "F.Fab")
		)
		(fp_line
			(start 0.120396 0.3048)
			(end 0.120396 0.2794)
			(stroke
				(width 0.1)
				(type default)
			)
			(layer "F.Fab")
		)
		(fp_line
			(start 0.12065 -0.3048)
			(end 0.67945 -0.3048)
			(stroke
				(width 0.1)
				(type default)
			)
			(layer "F.Fab")
		)
		(fp_line
			(start 0.12065 -0.2794)
			(end 0.12065 -0.3048)
			(stroke
				(width 0.1)
				(type default)
			)
			(layer "F.Fab")
		)
		(fp_line
			(start 0.67945 -0.3048)
			(end 0.67945 0.3048)
			(stroke
				(width 0.1)
				(type default)
			)
			(layer "F.Fab")
		)
		(fp_line
			(start 0.67945 0.3048)
			(end 0.120396 0.3048)
			(stroke
				(width 0.1)
				(type default)
			)
			(layer "F.Fab")
		)
		(pad "1" smd circle
			(at -0.40005 0)
			(size 0 0)
			(layers "F.Cu" "F.Mask" "F.Paste")
			(net "P3V3_RTC_AUX")
		)
		(pad "2" smd circle
			(at 0.40005 0)
			(size 0 0)
			(layers "F.Cu" "F.Mask" "F.Paste")
			(net "RST_SRTCRST_N")
		)
	)
	(footprint ""
		(layer "F.Cu")
		(at 123.96978 -113.121948 -90)
		(property "Reference" "U305"
			(at -2.09169 -3.21818 0)
			(unlocked yes)
			(layer "F.SilkS")
			(effects
				(font
					(size 0.7874 0.5842)
					(thickness 0.1524)
				)
				(justify left)
			)
		)
		(property "Value" ""
			(at 0 0 270)
			(layer "F.Fab")
			(effects
				(font
					(size 1.27 1.27)
				)
			)
		)
		(duplicate_pad_numbers_are_jumpers no)
		(fp_line
			(start -2.0066 2.5527)
			(end -2.0066 -2.5527)
			(stroke
				(width 0.1524)
				(type default)
			)
			(layer "F.SilkS")
		)
		(fp_line
			(start 2.0066 2.5527)
			(end -2.0066 2.5527)
			(stroke
				(width 0.1524)
				(type default)
			)
			(layer "F.SilkS")
		)
		(fp_line
			(start 0 -1.9812)
			(end 0.5715 -2.5527)
			(stroke
				(width 0.1524)
				(type default)
			)
			(layer "F.SilkS")
		)
		(fp_line
			(start -2.0066 -2.5527)
			(end -0.5715 -2.5527)
			(stroke
				(width 0.1524)
				(type default)
			)
			(layer "F.SilkS")
		)
		(fp_line
			(start -0.5715 -2.5527)
			(end 0 -1.9812)
			(stroke
				(width 0.1524)
				(type default)
			)
			(layer "F.SilkS")
		)
		(fp_line
			(start 0.5715 -2.5527)
			(end 2.0066 -2.5527)
			(stroke
				(width 0.1524)
				(type default)
			)
			(layer "F.SilkS")
		)
		(fp_line
			(start 2.0066 -2.5527)
			(end 2.0066 2.5527)
			(stroke
				(width 0.1524)
				(type default)
			)
			(layer "F.SilkS")
		)
		(fp_poly
			(pts
				(xy -4.36372 -2.233168) (xy -3.81 -1.905) (xy -4.36372 -1.608328)
			)
			(stroke
				(width 0)
				(type default)
			)
			(fill yes)
			(layer "F.SilkS")
		)
		(fp_line
			(start -2.249932 2.549906)
			(end -2.249932 -2.549906)
			(stroke
				(width 0.1)
				(type default)
			)
			(layer "F.Fab")
		)
		(fp_line
			(start 2.249932 2.549906)
			(end -2.249932 2.549906)
			(stroke
				(width 0.1)
				(type default)
			)
			(layer "F.Fab")
		)
		(fp_line
			(start -2.249932 -2.549906)
			(end 2.249932 -2.549906)
			(stroke
				(width 0.1)
				(type default)
			)
			(layer "F.Fab")
		)
		(fp_line
			(start 2.249932 -2.549906)
			(end 2.249932 2.549906)
			(stroke
				(width 0.1)
				(type default)
			)
			(layer "F.Fab")
		)
		(fp_poly
			(pts
				(xy -4.36372 -1.608328) (xy -4.36372 -2.233168) (xy -3.81 -1.905)
			)
			(stroke
				(width 0)
				(type default)
			)
			(fill yes)
			(layer "F.Fab")
		)
		(pad "1" smd rect
			(at -2.921 -1.949958 180)
			(size 0.3556 1.4986)
			(layers "F.Cu" "F.Mask" "F.Paste")
			(net "PD_GTL2014_BMC_JTAG_DIR_1")
		)
		(pad "2" smd rect
			(at -2.921 -1.299972 180)
			(size 0.3556 1.4986)
			(layers "F.Cu" "F.Mask" "F.Paste")
			(net "RST_CPU1_DRAM_GH_PLD_N")
		)
		(pad "3" smd rect
			(at -2.921 -0.649986 180)
			(size 0.3556 1.4986)
			(layers "F.Cu" "F.Mask" "F.Paste")
			(net "RST_CPU1_DRAM_EF_PLD_N")
		)
		(pad "4" smd rect
			(at -2.921 0 180)
			(size 0.3556 1.4986)
			(layers "F.Cu" "F.Mask" "F.Paste")
			(net "P0V62_CPU1_RST_DDR_VREF")
		)
		(pad "5" smd rect
			(at -2.921 0.649986 180)
			(size 0.3556 1.4986)
			(layers "F.Cu" "F.Mask" "F.Paste")
			(net "RST_CPU1_DRAM_CD_PLD_N")
		)
		(pad "6" smd rect
			(at -2.921 1.299972 180)
			(size 0.3556 1.4986)
			(layers "F.Cu" "F.Mask" "F.Paste")
			(net "RST_CPU1_DRAM_AB_PLD_N")
		)
		(pad "7" smd rect
			(at -2.921 1.949958 180)
			(size 0.3556 1.4986)
			(layers "F.Cu" "F.Mask" "F.Paste")
			(net "GND")
		)
		(pad "8" smd rect
			(at 2.921 1.949958 180)
			(size 0.3556 1.4986)
			(layers "F.Cu" "F.Mask" "F.Paste")
			(net "GND")
		)
		(pad "9" smd rect
			(at 2.921 1.299972 180)
			(size 0.3556 1.4986)
			(layers "F.Cu" "F.Mask" "F.Paste")
			(net "RST_CPU1_DRAM_AB_PLD_LVT3_R_N")
		)
		(pad "10" smd rect
			(at 2.921 0.649986 180)
			(size 0.3556 1.4986)
			(layers "F.Cu" "F.Mask" "F.Paste")
			(net "RST_CPU1_DRAM_CD_PLD_LVT3_R_N")
		)
		(pad "11" smd rect
			(at 2.921 0 180)
			(size 0.3556 1.4986)
			(layers "F.Cu" "F.Mask" "F.Paste")
			(net "GND")
		)
		(pad "12" smd rect
			(at 2.921 -0.649986 180)
			(size 0.3556 1.4986)
			(layers "F.Cu" "F.Mask" "F.Paste")
			(net "RST_CPU1_DRAM_EF_PLD_LVT3_R_N")
		)
		(pad "13" smd rect
			(at 2.921 -1.299972 180)
			(size 0.3556 1.4986)
			(layers "F.Cu" "F.Mask" "F.Paste")
			(net "RST_CPU1_DRAM_GH_PLD_LVT3_R_N")
		)
		(pad "14" smd rect
			(at 2.921 -1.949958 180)
			(size 0.3556 1.4986)
			(layers "F.Cu" "F.Mask" "F.Paste")
			(net "P3V3_AUX")
		)
	)
	(footprint ""
		(layer "F.Cu")
		(at 391.08888 -148.808948 -90)
		(property "Reference" "R1648"
			(at 0 0 270)
			(layer "F.SilkS")
			(hide yes)
			(effects
				(font
					(size 1.27 1.27)
				)
			)
		)
		(property "Value" ""
			(at 0 0 270)
			(layer "F.Fab")
			(effects
				(font
					(size 1.27 1.27)
				)
			)
		)
		(duplicate_pad_numbers_are_jumpers no)
		(fp_line
			(start -0.7874 0.4064)
			(end -0.7874 -0.4064)
			(stroke
				(width 0.1524)
				(type default)
			)
			(layer "F.SilkS")
		)
		(fp_line
			(start 0.7874 0.4064)
			(end -0.7874 0.4064)
			(stroke
				(width 0.1524)
				(type default)
			)
			(layer "F.SilkS")
		)
		(fp_line
			(start -0.7874 -0.4064)
			(end 0.7874 -0.4064)
			(stroke
				(width 0.1524)
				(type default)
			)
			(layer "F.SilkS")
		)
		(fp_line
			(start 0.7874 -0.4064)
			(end 0.7874 0.4064)
			(stroke
				(width 0.1524)
				(type default)
			)
			(layer "F.SilkS")
		)
		(fp_line
			(start -0.67945 0.3048)
			(end -0.67945 -0.305054)
			(stroke
				(width 0.1)
				(type default)
			)
			(layer "F.Fab")
		)
		(fp_line
			(start -0.12065 0.3048)
			(end -0.67945 0.3048)
			(stroke
				(width 0.1)
				(type default)
			)
			(layer "F.Fab")
		)
		(fp_line
			(start 0.120396 0.3048)
			(end 0.120396 0.2794)
			(stroke
				(width 0.1)
				(type default)
			)
			(layer "F.Fab")
		)
		(fp_line
			(start 0.67945 0.3048)
			(end 0.120396 0.3048)
			(stroke
				(width 0.1)
				(type default)
			)
			(layer "F.Fab")
		)
		(fp_line
			(start -0.12065 0.2794)
			(end -0.12065 0.3048)
			(stroke
				(width 0.1)
				(type default)
			)
			(layer "F.Fab")
		)
		(fp_line
			(start 0.120396 0.2794)
			(end -0.12065 0.2794)
			(stroke
				(width 0.1)
				(type default)
			)
			(layer "F.Fab")
		)
		(fp_line
			(start -0.12065 -0.2794)
			(end 0.12065 -0.2794)
			(stroke
				(width 0.1)
				(type default)
			)
			(layer "F.Fab")
		)
		(fp_line
			(start 0.12065 -0.2794)
			(end 0.12065 -0.3048)
			(stroke
				(width 0.1)
				(type default)
			)
			(layer "F.Fab")
		)
		(fp_line
			(start 0.12065 -0.3048)
			(end 0.67945 -0.3048)
			(stroke
				(width 0.1)
				(type default)
			)
			(layer "F.Fab")
		)
		(fp_line
			(start 0.67945 -0.3048)
			(end 0.67945 0.3048)
			(stroke
				(width 0.1)
				(type default)
			)
			(layer "F.Fab")
		)
		(fp_line
			(start -0.67945 -0.305054)
			(end -0.12065 -0.305054)
			(stroke
				(width 0.1)
				(type default)
			)
			(layer "F.Fab")
		)
		(fp_line
			(start -0.12065 -0.305054)
			(end -0.12065 -0.2794)
			(stroke
				(width 0.1)
				(type default)
			)
			(layer "F.Fab")
		)
		(pad "1" smd circle
			(at -0.40005 0 270)
			(size 0 0)
			(layers "F.Cu" "F.Mask" "F.Paste")
			(net "SMB_S3M_CPU0_3V3AUX_SDA")
		)
		(pad "2" smd circle
			(at 0.40005 0 270)
			(size 0 0)
			(layers "F.Cu" "F.Mask" "F.Paste")
			(net "SMB_S3M_CPU1_3V3AUX_SDA")
		)
	)
	(footprint ""
		(layer "F.Cu")
		(at 62.861698 -26.99004 90)
		(property "Reference" "PR3853"
			(at 0 0 90)
			(layer "F.SilkS")
			(hide yes)
			(effects
				(font
					(size 1.27 1.27)
				)
			)
		)
		(property "Value" ""
			(at 0 0 90)
			(layer "F.Fab")
			(effects
				(font
					(size 1.27 1.27)
				)
			)
		)
		(duplicate_pad_numbers_are_jumpers no)
		(fp_line
			(start 0.7874 -0.4064)
			(end 0.7874 0.4064)
			(stroke
				(width 0.1524)
				(type default)
			)
			(layer "F.SilkS")
		)
		(fp_line
			(start -0.7874 -0.4064)
			(end 0.7874 -0.4064)
			(stroke
				(width 0.1524)
				(type default)
			)
			(layer "F.SilkS")
		)
		(fp_line
			(start 0.7874 0.4064)
			(end -0.7874 0.4064)
			(stroke
				(width 0.1524)
				(type default)
			)
			(layer "F.SilkS")
		)
		(fp_line
			(start -0.7874 0.4064)
			(end -0.7874 -0.4064)
			(stroke
				(width 0.1524)
				(type default)
			)
			(layer "F.SilkS")
		)
		(fp_line
			(start -0.12065 -0.305054)
			(end -0.12065 -0.2794)
			(stroke
				(width 0.1)
				(type default)
			)
			(layer "F.Fab")
		)
		(fp_line
			(start -0.67945 -0.305054)
			(end -0.12065 -0.305054)
			(stroke
				(width 0.1)
				(type default)
			)
			(layer "F.Fab")
		)
		(fp_line
			(start 0.67945 -0.3048)
			(end 0.67945 0.3048)
			(stroke
				(width 0.1)
				(type default)
			)
			(layer "F.Fab")
		)
		(fp_line
			(start 0.12065 -0.3048)
			(end 0.67945 -0.3048)
			(stroke
				(width 0.1)
				(type default)
			)
			(layer "F.Fab")
		)
		(fp_line
			(start 0.12065 -0.2794)
			(end 0.12065 -0.3048)
			(stroke
				(width 0.1)
				(type default)
			)
			(layer "F.Fab")
		)
		(fp_line
			(start -0.12065 -0.2794)
			(end 0.12065 -0.2794)
			(stroke
				(width 0.1)
				(type default)
			)
			(layer "F.Fab")
		)
		(fp_line
			(start 0.120396 0.2794)
			(end -0.12065 0.2794)
			(stroke
				(width 0.1)
				(type default)
			)
			(layer "F.Fab")
		)
		(fp_line
			(start -0.12065 0.2794)
			(end -0.12065 0.3048)
			(stroke
				(width 0.1)
				(type default)
			)
			(layer "F.Fab")
		)
		(fp_line
			(start 0.67945 0.3048)
			(end 0.120396 0.3048)
			(stroke
				(width 0.1)
				(type default)
			)
			(layer "F.Fab")
		)
		(fp_line
			(start 0.120396 0.3048)
			(end 0.120396 0.2794)
			(stroke
				(width 0.1)
				(type default)
			)
			(layer "F.Fab")
		)
		(fp_line
			(start -0.12065 0.3048)
			(end -0.67945 0.3048)
			(stroke
				(width 0.1)
				(type default)
			)
			(layer "F.Fab")
		)
		(fp_line
			(start -0.67945 0.3048)
			(end -0.67945 -0.305054)
			(stroke
				(width 0.1)
				(type default)
			)
			(layer "F.Fab")
		)
		(pad "1" smd circle
			(at -0.40005 0 90)
			(size 0 0)
			(layers "F.Cu" "F.Mask" "F.Paste")
			(net "P12V_AUX")
		)
		(pad "2" smd circle
			(at 0.40005 0 90)
			(size 0 0)
			(layers "F.Cu" "F.Mask" "F.Paste")
			(net "P12V_OCP_OV_FB_2")
		)
	)
)
